(kicad_pcb
	(version 20260206)
	(generator "pcbnew")
	(generator_version "10.0")
	(general
		(thickness 1.6)
		(legacy_teardrops no)
	)
	(paper "A4")
	(title_block
		(title "04192023_DAF0TMB3IC0_F0TG_MB_C_brd_V02_OCP.brd")
		(comment 1 "Grand Teton / footprints 7151-7156 of 8354")
	)
	(layers
		(0 "F.Cu" signal "TOP")
		(4 "In1.Cu" signal "GND")
		(6 "In2.Cu" signal "IN1")
		(8 "In3.Cu" signal "GND1")
		(10 "In4.Cu" signal "IN2")
		(12 "In5.Cu" signal "GND2")
		(14 "In6.Cu" signal "IN3")
		(16 "In7.Cu" signal "GND3")
		(18 "In8.Cu" signal "VCC")
		(20 "In9.Cu" signal "VCC1")
		(22 "In10.Cu" signal "GND4")
		(24 "In11.Cu" signal "IN4")
		(26 "In12.Cu" signal "GND5")
		(28 "In13.Cu" signal "IN5")
		(30 "In14.Cu" signal "GND6")
		(32 "In15.Cu" signal "IN6")
		(34 "In16.Cu" signal "GND7")
		(2 "B.Cu" signal "BOTTOM")
		(9 "F.Adhes" user "F.Adhesive")
		(11 "B.Adhes" user "B.Adhesive")
		(13 "F.Paste" user "Package Geometry/Pastemask Top")
		(15 "B.Paste" user "Package Geometry/Pastemask Bottom")
		(5 "F.SilkS" user "Ref Des/Silkscreen Top")
		(7 "B.SilkS" user "Ref Des/Silkscreen Bottom")
		(1 "F.Mask" user "Board Geometry/Soldermask Top")
		(3 "B.Mask" user "Board Geometry/Soldermask Bottom")
		(17 "Dwgs.User" user "User.Drawings")
		(19 "Cmts.User" user "User.Comments")
		(21 "Eco1.User" user "User.Eco1")
		(23 "Eco2.User" user "User.Eco2")
		(25 "Edge.Cuts" user "Board Geometry/Outline")
		(27 "Margin" user)
		(31 "F.CrtYd" user "Package Geometry/Place Bound Top")
		(29 "B.CrtYd" user "Package Geometry/Place Bound Bottom")
		(35 "F.Fab" user "Ref Des/Assembly Top")
		(33 "B.Fab" user "Ref Des/Assembly Bottom")
	)
	(footprint ""
		(layer "B.Cu")
		(at 115.70589 -257.74523 180)
		(property "Reference" "C2407"
			(at 0 0 0)
			(layer "B.SilkS")
			(hide yes)
			(effects
				(font
					(size 1.27 1.27)
				)
				(justify mirror)
			)
		)
		(property "Value" ""
			(at 0 0 0)
			(layer "B.Fab")
			(effects
				(font
					(size 1.27 1.27)
				)
				(justify mirror)
			)
		)
		(duplicate_pad_numbers_are_jumpers no)
		(fp_line
			(start 0.7874 0.4064)
			(end 0.7874 -0.4064)
			(stroke
				(width 0.1524)
				(type default)
			)
			(layer "B.SilkS")
		)
		(fp_line
			(start 0.7874 -0.4064)
			(end -0.7874 -0.4064)
			(stroke
				(width 0.1524)
				(type default)
			)
			(layer "B.SilkS")
		)
		(fp_line
			(start -0.7874 0.4064)
			(end 0.7874 0.4064)
			(stroke
				(width 0.1524)
				(type default)
			)
			(layer "B.SilkS")
		)
		(fp_line
			(start -0.7874 -0.4064)
			(end -0.7874 0.4064)
			(stroke
				(width 0.1524)
				(type default)
			)
			(layer "B.SilkS")
		)
		(fp_line
			(start 0.67945 0.3048)
			(end 0.67945 -0.305054)
			(stroke
				(width 0.1)
				(type default)
			)
			(layer "B.Fab")
		)
		(fp_line
			(start 0.67945 -0.305054)
			(end 0.12065 -0.305054)
			(stroke
				(width 0.1)
				(type default)
			)
			(layer "B.Fab")
		)
		(fp_line
			(start 0.12065 0.3048)
			(end 0.67945 0.3048)
			(stroke
				(width 0.1)
				(type default)
			)
			(layer "B.Fab")
		)
		(fp_line
			(start 0.12065 0.2794)
			(end 0.12065 0.3048)
			(stroke
				(width 0.1)
				(type default)
			)
			(layer "B.Fab")
		)
		(fp_line
			(start 0.12065 -0.2794)
			(end -0.12065 -0.2794)
			(stroke
				(width 0.1)
				(type default)
			)
			(layer "B.Fab")
		)
		(fp_line
			(start 0.12065 -0.305054)
			(end 0.12065 -0.2794)
			(stroke
				(width 0.1)
				(type default)
			)
			(layer "B.Fab")
		)
		(fp_line
			(start -0.120396 0.3048)
			(end -0.120396 0.2794)
			(stroke
				(width 0.1)
				(type default)
			)
			(layer "B.Fab")
		)
		(fp_line
			(start -0.120396 0.2794)
			(end 0.12065 0.2794)
			(stroke
				(width 0.1)
				(type default)
			)
			(layer "B.Fab")
		)
		(fp_line
			(start -0.12065 -0.2794)
			(end -0.12065 -0.3048)
			(stroke
				(width 0.1)
				(type default)
			)
			(layer "B.Fab")
		)
		(fp_line
			(start -0.12065 -0.3048)
			(end -0.67945 -0.3048)
			(stroke
				(width 0.1)
				(type default)
			)
			(layer "B.Fab")
		)
		(fp_line
			(start -0.67945 0.3048)
			(end -0.120396 0.3048)
			(stroke
				(width 0.1)
				(type default)
			)
			(layer "B.Fab")
		)
		(fp_line
			(start -0.67945 -0.3048)
			(end -0.67945 0.3048)
			(stroke
				(width 0.1)
				(type default)
			)
			(layer "B.Fab")
		)
		(pad "1" smd circle
			(at 0.40005 0)
			(size 0 0)
			(layers "B.Cu" "B.Mask" "B.Paste")
			(net "PVDDCR_SOC_P1")
		)
		(pad "2" smd circle
			(at -0.40005 0)
			(size 0 0)
			(layers "B.Cu" "B.Mask" "B.Paste")
			(net "GND")
		)
	)
	(footprint ""
		(layer "B.Cu")
		(at 203.897484 -341.853012 180)
		(property "Reference" "PR6000"
			(at 0 0 0)
			(layer "B.SilkS")
			(hide yes)
			(effects
				(font
					(size 1.27 1.27)
				)
				(justify mirror)
			)
		)
		(property "Value" ""
			(at 0 0 0)
			(layer "B.Fab")
			(effects
				(font
					(size 1.27 1.27)
				)
				(justify mirror)
			)
		)
		(duplicate_pad_numbers_are_jumpers no)
		(fp_line
			(start 0.7874 0.4064)
			(end 0.7874 -0.4064)
			(stroke
				(width 0.1524)
				(type default)
			)
			(layer "B.SilkS")
		)
		(fp_line
			(start 0.7874 -0.4064)
			(end -0.7874 -0.4064)
			(stroke
				(width 0.1524)
				(type default)
			)
			(layer "B.SilkS")
		)
		(fp_line
			(start -0.7874 0.4064)
			(end 0.7874 0.4064)
			(stroke
				(width 0.1524)
				(type default)
			)
			(layer "B.SilkS")
		)
		(fp_line
			(start -0.7874 -0.4064)
			(end -0.7874 0.4064)
			(stroke
				(width 0.1524)
				(type default)
			)
			(layer "B.SilkS")
		)
		(fp_line
			(start 0.67945 0.3048)
			(end 0.67945 -0.305054)
			(stroke
				(width 0.1)
				(type default)
			)
			(layer "B.Fab")
		)
		(fp_line
			(start 0.67945 -0.305054)
			(end 0.12065 -0.305054)
			(stroke
				(width 0.1)
				(type default)
			)
			(layer "B.Fab")
		)
		(fp_line
			(start 0.12065 0.3048)
			(end 0.67945 0.3048)
			(stroke
				(width 0.1)
				(type default)
			)
			(layer "B.Fab")
		)
		(fp_line
			(start 0.12065 0.2794)
			(end 0.12065 0.3048)
			(stroke
				(width 0.1)
				(type default)
			)
			(layer "B.Fab")
		)
		(fp_line
			(start 0.12065 -0.2794)
			(end -0.12065 -0.2794)
			(stroke
				(width 0.1)
				(type default)
			)
			(layer "B.Fab")
		)
		(fp_line
			(start 0.12065 -0.305054)
			(end 0.12065 -0.2794)
			(stroke
				(width 0.1)
				(type default)
			)
			(layer "B.Fab")
		)
		(fp_line
			(start -0.120396 0.3048)
			(end -0.120396 0.2794)
			(stroke
				(width 0.1)
				(type default)
			)
			(layer "B.Fab")
		)
		(fp_line
			(start -0.120396 0.2794)
			(end 0.12065 0.2794)
			(stroke
				(width 0.1)
				(type default)
			)
			(layer "B.Fab")
		)
		(fp_line
			(start -0.12065 -0.2794)
			(end -0.12065 -0.3048)
			(stroke
				(width 0.1)
				(type default)
			)
			(layer "B.Fab")
		)
		(fp_line
			(start -0.12065 -0.3048)
			(end -0.67945 -0.3048)
			(stroke
				(width 0.1)
				(type default)
			)
			(layer "B.Fab")
		)
		(fp_line
			(start -0.67945 0.3048)
			(end -0.120396 0.3048)
			(stroke
				(width 0.1)
				(type default)
			)
			(layer "B.Fab")
		)
		(fp_line
			(start -0.67945 -0.3048)
			(end -0.67945 0.3048)
			(stroke
				(width 0.1)
				(type default)
			)
			(layer "B.Fab")
		)
		(pad "1" smd circle
			(at 0.40005 0)
			(size 0 0)
			(layers "B.Cu" "B.Mask" "B.Paste")
			(net "GND")
		)
		(pad "2" smd circle
			(at -0.40005 0)
			(size 0 0)
			(layers "B.Cu" "B.Mask" "B.Paste")
			(net "PVDD_33_S5_MODE")
		)
	)
	(footprint ""
		(layer "B.Cu")
		(at 234.569 -241.2111 90)
		(property "Reference" "R338"
			(at 0 0 90)
			(layer "B.SilkS")
			(hide yes)
			(effects
				(font
					(size 1.27 1.27)
				)
				(justify mirror)
			)
		)
		(property "Value" ""
			(at 0 0 90)
			(layer "B.Fab")
			(effects
				(font
					(size 1.27 1.27)
				)
				(justify mirror)
			)
		)
		(duplicate_pad_numbers_are_jumpers no)
		(fp_line
			(start 0.7874 -0.4064)
			(end -0.7874 -0.4064)
			(stroke
				(width 0.1524)
				(type default)
			)
			(layer "B.SilkS")
		)
		(fp_line
			(start -0.7874 -0.4064)
			(end -0.7874 0.4064)
			(stroke
				(width 0.1524)
				(type default)
			)
			(layer "B.SilkS")
		)
		(fp_line
			(start 0.7874 0.4064)
			(end 0.7874 -0.4064)
			(stroke
				(width 0.1524)
				(type default)
			)
			(layer "B.SilkS")
		)
		(fp_line
			(start -0.7874 0.4064)
			(end 0.7874 0.4064)
			(stroke
				(width 0.1524)
				(type default)
			)
			(layer "B.SilkS")
		)
		(fp_line
			(start 0.67945 -0.305054)
			(end 0.12065 -0.305054)
			(stroke
				(width 0.1)
				(type default)
			)
			(layer "B.Fab")
		)
		(fp_line
			(start 0.12065 -0.305054)
			(end 0.12065 -0.2794)
			(stroke
				(width 0.1)
				(type default)
			)
			(layer "B.Fab")
		)
		(fp_line
			(start -0.12065 -0.3048)
			(end -0.67945 -0.3048)
			(stroke
				(width 0.1)
				(type default)
			)
			(layer "B.Fab")
		)
		(fp_line
			(start -0.67945 -0.3048)
			(end -0.67945 0.3048)
			(stroke
				(width 0.1)
				(type default)
			)
			(layer "B.Fab")
		)
		(fp_line
			(start 0.12065 -0.2794)
			(end -0.12065 -0.2794)
			(stroke
				(width 0.1)
				(type default)
			)
			(layer "B.Fab")
		)
		(fp_line
			(start -0.12065 -0.2794)
			(end -0.12065 -0.3048)
			(stroke
				(width 0.1)
				(type default)
			)
			(layer "B.Fab")
		)
		(fp_line
			(start 0.12065 0.2794)
			(end 0.12065 0.3048)
			(stroke
				(width 0.1)
				(type default)
			)
			(layer "B.Fab")
		)
		(fp_line
			(start -0.120396 0.2794)
			(end 0.12065 0.2794)
			(stroke
				(width 0.1)
				(type default)
			)
			(layer "B.Fab")
		)
		(fp_line
			(start 0.67945 0.3048)
			(end 0.67945 -0.305054)
			(stroke
				(width 0.1)
				(type default)
			)
			(layer "B.Fab")
		)
		(fp_line
			(start 0.12065 0.3048)
			(end 0.67945 0.3048)
			(stroke
				(width 0.1)
				(type default)
			)
			(layer "B.Fab")
		)
		(fp_line
			(start -0.120396 0.3048)
			(end -0.120396 0.2794)
			(stroke
				(width 0.1)
				(type default)
			)
			(layer "B.Fab")
		)
		(fp_line
			(start -0.67945 0.3048)
			(end -0.120396 0.3048)
			(stroke
				(width 0.1)
				(type default)
			)
			(layer "B.Fab")
		)
		(pad "1" smd rect
			(at 0.40005 0 90)
			(size 0.4572 0.508)
			(layers "B.Cu" "B.Mask" "B.Paste")
			(net "SMB_APML_CPU1_MUX2_SDA")
		)
		(pad "2" smd rect
			(at -0.40005 0 90)
			(size 0.4572 0.508)
			(layers "B.Cu" "B.Mask" "B.Paste")
			(net "SMB_APML_CPU1_SDA")
		)
	)
	(footprint ""
		(layer "B.Cu")
		(at 354.628958 -249.36831 180)
		(property "Reference" "C273"
			(at 0 0 0)
			(layer "B.SilkS")
			(hide yes)
			(effects
				(font
					(size 1.27 1.27)
				)
				(justify mirror)
			)
		)
		(property "Value" ""
			(at 0 0 0)
			(layer "B.Fab")
			(effects
				(font
					(size 1.27 1.27)
				)
				(justify mirror)
			)
		)
		(duplicate_pad_numbers_are_jumpers no)
		(fp_line
			(start 0.7874 0.4064)
			(end 0.7874 -0.4064)
			(stroke
				(width 0.1524)
				(type default)
			)
			(layer "B.SilkS")
		)
		(fp_line
			(start 0.7874 -0.4064)
			(end -0.7874 -0.4064)
			(stroke
				(width 0.1524)
				(type default)
			)
			(layer "B.SilkS")
		)
		(fp_line
			(start -0.7874 0.4064)
			(end 0.7874 0.4064)
			(stroke
				(width 0.1524)
				(type default)
			)
			(layer "B.SilkS")
		)
		(fp_line
			(start -0.7874 -0.4064)
			(end -0.7874 0.4064)
			(stroke
				(width 0.1524)
				(type default)
			)
			(layer "B.SilkS")
		)
		(fp_line
			(start 0.67945 0.3048)
			(end 0.67945 -0.305054)
			(stroke
				(width 0.1)
				(type default)
			)
			(layer "B.Fab")
		)
		(fp_line
			(start 0.67945 -0.305054)
			(end 0.12065 -0.305054)
			(stroke
				(width 0.1)
				(type default)
			)
			(layer "B.Fab")
		)
		(fp_line
			(start 0.12065 0.3048)
			(end 0.67945 0.3048)
			(stroke
				(width 0.1)
				(type default)
			)
			(layer "B.Fab")
		)
		(fp_line
			(start 0.12065 0.2794)
			(end 0.12065 0.3048)
			(stroke
				(width 0.1)
				(type default)
			)
			(layer "B.Fab")
		)
		(fp_line
			(start 0.12065 -0.2794)
			(end -0.12065 -0.2794)
			(stroke
				(width 0.1)
				(type default)
			)
			(layer "B.Fab")
		)
		(fp_line
			(start 0.12065 -0.305054)
			(end 0.12065 -0.2794)
			(stroke
				(width 0.1)
				(type default)
			)
			(layer "B.Fab")
		)
		(fp_line
			(start -0.120396 0.3048)
			(end -0.120396 0.2794)
			(stroke
				(width 0.1)
				(type default)
			)
			(layer "B.Fab")
		)
		(fp_line
			(start -0.120396 0.2794)
			(end 0.12065 0.2794)
			(stroke
				(width 0.1)
				(type default)
			)
			(layer "B.Fab")
		)
		(fp_line
			(start -0.12065 -0.2794)
			(end -0.12065 -0.3048)
			(stroke
				(width 0.1)
				(type default)
			)
			(layer "B.Fab")
		)
		(fp_line
			(start -0.12065 -0.3048)
			(end -0.67945 -0.3048)
			(stroke
				(width 0.1)
				(type default)
			)
			(layer "B.Fab")
		)
		(fp_line
			(start -0.67945 0.3048)
			(end -0.120396 0.3048)
			(stroke
				(width 0.1)
				(type default)
			)
			(layer "B.Fab")
		)
		(fp_line
			(start -0.67945 -0.3048)
			(end -0.67945 0.3048)
			(stroke
				(width 0.1)
				(type default)
			)
			(layer "B.Fab")
		)
		(pad "1" smd circle
			(at 0.40005 0)
			(size 0 0)
			(layers "B.Cu" "B.Mask" "B.Paste")
			(net "PVDDCR_CPU0_P0")
		)
		(pad "2" smd circle
			(at -0.40005 0)
			(size 0 0)
			(layers "B.Cu" "B.Mask" "B.Paste")
			(net "GND")
		)
	)
	(footprint ""
		(layer "B.Cu")
		(at 395.179296 -154.065986 180)
		(property "Reference" "U324"
			(at -0.98298 -2.36347 0)
			(unlocked yes)
			(layer "B.SilkS")
			(effects
				(font
					(size 0.7874 0.5842)
					(thickness 0.1524)
				)
				(justify left mirror)
			)
		)
		(property "Value" ""
			(at 0 0 0)
			(layer "B.Fab")
			(effects
				(font
					(size 1.27 1.27)
				)
				(justify mirror)
			)
		)
		(duplicate_pad_numbers_are_jumpers no)
		(fp_line
			(start 1.603248 1.500124)
			(end 1.603248 -1.500124)
			(stroke
				(width 0.1524)
				(type default)
			)
			(layer "B.SilkS")
		)
		(fp_line
			(start 1.603248 -1.500124)
			(end -1.603248 -1.500124)
			(stroke
				(width 0.1524)
				(type default)
			)
			(layer "B.SilkS")
		)
		(fp_line
			(start -1.603248 1.500124)
			(end 1.603248 1.500124)
			(stroke
				(width 0.1524)
				(type default)
			)
			(layer "B.SilkS")
		)
		(fp_line
			(start -1.603248 -1.500124)
			(end -1.603248 1.500124)
			(stroke
				(width 0.1524)
				(type default)
			)
			(layer "B.SilkS")
		)
		(fp_line
			(start 1.249934 1.169924)
			(end 0.700024 1.169924)
			(stroke
				(width 0.1)
				(type default)
			)
			(layer "B.Fab")
		)
		(fp_line
			(start 1.249934 0.729996)
			(end 1.249934 1.169924)
			(stroke
				(width 0.1)
				(type default)
			)
			(layer "B.Fab")
		)
		(fp_line
			(start 1.249934 -0.729996)
			(end 0.6985 -0.729996)
			(stroke
				(width 0.1)
				(type default)
			)
			(layer "B.Fab")
		)
		(fp_line
			(start 1.249934 -1.169924)
			(end 1.249934 -0.729996)
			(stroke
				(width 0.1)
				(type default)
			)
			(layer "B.Fab")
		)
		(fp_line
			(start 0.700024 1.500124)
			(end -0.700024 1.500124)
			(stroke
				(width 0.1)
				(type default)
			)
			(layer "B.Fab")
		)
		(fp_line
			(start 0.700024 1.169924)
			(end 0.700024 1.500124)
			(stroke
				(width 0.1)
				(type default)
			)
			(layer "B.Fab")
		)
		(fp_line
			(start 0.700024 -1.169924)
			(end 1.249934 -1.169924)
			(stroke
				(width 0.1)
				(type default)
			)
			(layer "B.Fab")
		)
		(fp_line
			(start 0.700024 -1.500124)
			(end 0.700024 -1.169924)
			(stroke
				(width 0.1)
				(type default)
			)
			(layer "B.Fab")
		)
		(fp_line
			(start 0.6985 0.729996)
			(end 1.249934 0.729996)
			(stroke
				(width 0.1)
				(type default)
			)
			(layer "B.Fab")
		)
		(fp_line
			(start 0.6985 -0.729996)
			(end 0.6985 0.729996)
			(stroke
				(width 0.1)
				(type default)
			)
			(layer "B.Fab")
		)
		(fp_line
			(start -0.700024 1.500124)
			(end -0.700024 0.219964)
			(stroke
				(width 0.1)
				(type default)
			)
			(layer "B.Fab")
		)
		(fp_line
			(start -0.700024 0.219964)
			(end -1.249934 0.219964)
			(stroke
				(width 0.1)
				(type default)
			)
			(layer "B.Fab")
		)
		(fp_line
			(start -0.700024 -0.219964)
			(end -0.700024 -1.500124)
			(stroke
				(width 0.1)
				(type default)
			)
			(layer "B.Fab")
		)
		(fp_line
			(start -0.700024 -1.500124)
			(end 0.700024 -1.500124)
			(stroke
				(width 0.1)
				(type default)
			)
			(layer "B.Fab")
		)
		(fp_line
			(start -1.249934 0.219964)
			(end -1.249934 -0.219964)
			(stroke
				(width 0.1)
				(type default)
			)
			(layer "B.Fab")
		)
		(fp_line
			(start -1.249934 -0.219964)
			(end -0.700024 -0.219964)
			(stroke
				(width 0.1)
				(type default)
			)
			(layer "B.Fab")
		)
		(fp_rect
			(start -0.700024 1.500124)
			(end 0.700024 -1.500124)
			(stroke
				(width 0)
				(type default)
			)
			(fill no)
			(layer "B.Fab")
		)
		(pad "D" smd rect
			(at -0.999998 0 90)
			(size 0.8128 0.9144)
			(layers "B.Cu" "B.Mask" "B.Paste")
			(net "VR_P5V_EN_D")
		)
		(pad "G" smd rect
			(at 0.999998 -0.94996 90)
			(size 0.8128 0.9144)
			(layers "B.Cu" "B.Mask" "B.Paste")
			(net "VR_P5V_EN_N")
		)
		(pad "S" smd rect
			(at 0.999998 0.94996 90)
			(size 0.8128 0.9144)
			(layers "B.Cu" "B.Mask" "B.Paste")
			(net "GND")
		)
	)
	(footprint ""
		(layer "B.Cu")
		(at 186.711844 -113.462816 90)
		(property "Reference" "C358"
			(at 0 0 90)
			(layer "B.SilkS")
			(hide yes)
			(effects
				(font
					(size 1.27 1.27)
				)
				(justify mirror)
			)
		)
		(property "Value" ""
			(at 0 0 90)
			(layer "B.Fab")
			(effects
				(font
					(size 1.27 1.27)
				)
				(justify mirror)
			)
		)
		(duplicate_pad_numbers_are_jumpers no)
		(fp_line
			(start 0.69215 -0.2921)
			(end -0.69215 -0.2921)
			(stroke
				(width 0.1524)
				(type default)
			)
			(layer "B.SilkS")
		)
		(fp_line
			(start -0.69215 -0.2921)
			(end -0.69215 0.2921)
			(stroke
				(width 0.1524)
				(type default)
			)
			(layer "B.SilkS")
		)
		(fp_line
			(start 0.69215 0.2921)
			(end 0.69215 -0.2921)
			(stroke
				(width 0.1524)
				(type default)
			)
			(layer "B.SilkS")
		)
		(fp_line
			(start -0.69215 0.2921)
			(end 0.69215 0.2921)
			(stroke
				(width 0.1524)
				(type default)
			)
			(layer "B.SilkS")
		)
		(fp_line
			(start 0.51435 -0.2794)
			(end -0.51435 -0.2794)
			(stroke
				(width 0.1)
				(type default)
			)
			(layer "B.Fab")
		)
		(fp_line
			(start -0.51435 -0.2794)
			(end -0.51435 0.2794)
			(stroke
				(width 0.1)
				(type default)
			)
			(layer "B.Fab")
		)
		(fp_line
			(start 0.51435 0.2794)
			(end 0.51435 -0.2794)
			(stroke
				(width 0.1)
				(type default)
			)
			(layer "B.Fab")
		)
		(fp_line
			(start -0.51435 0.2794)
			(end 0.51435 0.2794)
			(stroke
				(width 0.1)
				(type default)
			)
			(layer "B.Fab")
		)
		(pad "1" smd circle
			(at 0.40005 0 270)
			(size 0 0)
			(layers "B.Cu" "B.Mask" "B.Paste")
			(net "P3V3_AUX")
		)
		(pad "2" smd circle
			(at -0.40005 0 270)
			(size 0 0)
			(layers "B.Cu" "B.Mask" "B.Paste")
			(net "GND")
		)
		(zone
			(layer "B.Cu")
			(hatch none 0.5)
			(connect_pads
				(clearance 0)
			)
			(min_thickness 0.25)
			(keepout
				(tracks not_allowed)
				(vias allowed)
				(pads allowed)
				(copperpour not_allowed)
				(footprints allowed)
			)
			(placement
				(enabled no)
				(sheetname "")
			)
			(fill
				(thermal_gap 0.5)
				(thermal_bridge_width 0.5)
				(island_removal_mode 0)
			)
			(polygon
				(pts
					(xy 186.565794 -113.362486) (xy 186.565794 -113.561876) (xy 186.62396 -113.653316) (xy 186.799474 -113.653316)
					(xy 186.85764 -113.561876) (xy 186.85764 -113.362486) (xy 186.799474 -113.272316) (xy 186.624214 -113.272316)
				)
			)
		)
	)
)
